# S9S_MB_2U (Grand Teton) — schematic netlist excerpt (pin names and nets, part order shuffled) for the footprints in the layout excerpt that follows; sources: Cadence DE-HDL packaged netlist, KiCad conversion of 03242023_DA0F0TMBIJ0_F0T_Motherboard_J_brd_V01_OCP.brd

R8  Q_RES  10K 1% CHIP  pkg 0402LF  page 204 : A = P3V3_AUX ; B = FM_PS_PWROK_DLY_R_SEL
PR1647  Q_RES  10K 1% EMPTY  pkg 0402LF  page 262 : A = P3V3_AUX ; B = FM_P1V05_PCH_AUX_R_EN

(kicad_pcb
	(version 20260206)
	(generator "pcbnew")
	(generator_version "10.0")
	(general
		(thickness 1.6)
		(legacy_teardrops no)
	)
	(paper "A4")
	(title_block
		(title "03242023_DA0F0TMBIJ0_F0T_Motherboard_J_brd_V01_OCP.brd")
		(comment 1 "Grand Teton / footprints 4433-4434 of 6105")
	)
	(layers
		(0 "F.Cu" signal "TOP")
		(4 "In1.Cu" signal "GND")
		(6 "In2.Cu" signal "IN1")
		(8 "In3.Cu" signal "GND1")
		(10 "In4.Cu" signal "IN2")
		(12 "In5.Cu" signal "GND2")
		(14 "In6.Cu" signal "IN3")
		(16 "In7.Cu" signal "GND3")
		(18 "In8.Cu" signal "VCC")
		(20 "In9.Cu" signal "VCC1")
		(22 "In10.Cu" signal "GND4")
		(24 "In11.Cu" signal "IN4")
		(26 "In12.Cu" signal "GND5")
		(28 "In13.Cu" signal "IN5")
		(30 "In14.Cu" signal "GND6")
		(32 "In15.Cu" signal "IN6")
		(34 "In16.Cu" signal "GND7")
		(2 "B.Cu" signal "BOTTOM")
		(9 "F.Adhes" user "F.Adhesive")
		(11 "B.Adhes" user "B.Adhesive")
		(13 "F.Paste" user "Package Geometry/Pastemask Top")
		(15 "B.Paste" user "Package Geometry/Pastemask Bottom")
		(5 "F.SilkS" user "Ref Des/Silkscreen Top")
		(7 "B.SilkS" user "Ref Des/Silkscreen Bottom")
		(1 "F.Mask" user "Board Geometry/Soldermask Top")
		(3 "B.Mask" user "Board Geometry/Soldermask Bottom")
		(17 "Dwgs.User" user "User.Drawings")
		(19 "Cmts.User" user "User.Comments")
		(21 "Eco1.User" user "User.Eco1")
		(23 "Eco2.User" user "User.Eco2")
		(25 "Edge.Cuts" user "Board Geometry/Outline")
		(27 "Margin" user)
		(31 "F.CrtYd" user "Package Geometry/Place Bound Top")
		(29 "B.CrtYd" user "Package Geometry/Place Bound Bottom")
		(35 "F.Fab" user "Ref Des/Assembly Top")
		(33 "B.Fab" user "Ref Des/Assembly Bottom")
	)
	(footprint ""
		(layer "B.Cu")
		(at 341.272114 -31.678372)
		(property "Reference" "R8"
			(at 0 0 0)
			(layer "B.SilkS")
			(hide yes)
			(effects
				(font
					(size 1.27 1.27)
				)
				(justify mirror)
			)
		)
		(property "Value" ""
			(at 0 0 0)
			(layer "B.Fab")
			(effects
				(font
					(size 1.27 1.27)
				)
				(justify mirror)
			)
		)
		(duplicate_pad_numbers_are_jumpers no)
		(fp_line
			(start -0.7874 -0.4064)
			(end -0.7874 0.4064)
			(stroke
				(width 0.1524)
				(type default)
			)
			(layer "B.SilkS")
		)
		(fp_line
			(start -0.7874 0.4064)
			(end 0.7874 0.4064)
			(stroke
				(width 0.1524)
				(type default)
			)
			(layer "B.SilkS")
		)
		(fp_line
			(start 0.7874 -0.4064)
			(end -0.7874 -0.4064)
			(stroke
				(width 0.1524)
				(type default)
			)
			(layer "B.SilkS")
		)
		(fp_line
			(start 0.7874 0.4064)
			(end 0.7874 -0.4064)
			(stroke
				(width 0.1524)
				(type default)
			)
			(layer "B.SilkS")
		)
		(fp_line
			(start -0.67945 -0.3048)
			(end -0.67945 0.3048)
			(stroke
				(width 0.1)
				(type default)
			)
			(layer "B.Fab")
		)
		(fp_line
			(start -0.67945 0.3048)
			(end -0.120396 0.3048)
			(stroke
				(width 0.1)
				(type default)
			)
			(layer "B.Fab")
		)
		(fp_line
			(start -0.12065 -0.3048)
			(end -0.67945 -0.3048)
			(stroke
				(width 0.1)
				(type default)
			)
			(layer "B.Fab")
		)
		(fp_line
			(start -0.12065 -0.2794)
			(end -0.12065 -0.3048)
			(stroke
				(width 0.1)
				(type default)
			)
			(layer "B.Fab")
		)
		(fp_line
			(start -0.120396 0.2794)
			(end 0.12065 0.2794)
			(stroke
				(width 0.1)
				(type default)
			)
			(layer "B.Fab")
		)
		(fp_line
			(start -0.120396 0.3048)
			(end -0.120396 0.2794)
			(stroke
				(width 0.1)
				(type default)
			)
			(layer "B.Fab")
		)
		(fp_line
			(start 0.12065 -0.305054)
			(end 0.12065 -0.2794)
			(stroke
				(width 0.1)
				(type default)
			)
			(layer "B.Fab")
		)
		(fp_line
			(start 0.12065 -0.2794)
			(end -0.12065 -0.2794)
			(stroke
				(width 0.1)
				(type default)
			)
			(layer "B.Fab")
		)
		(fp_line
			(start 0.12065 0.2794)
			(end 0.12065 0.3048)
			(stroke
				(width 0.1)
				(type default)
			)
			(layer "B.Fab")
		)
		(fp_line
			(start 0.12065 0.3048)
			(end 0.67945 0.3048)
			(stroke
				(width 0.1)
				(type default)
			)
			(layer "B.Fab")
		)
		(fp_line
			(start 0.67945 -0.305054)
			(end 0.12065 -0.305054)
			(stroke
				(width 0.1)
				(type default)
			)
			(layer "B.Fab")
		)
		(fp_line
			(start 0.67945 0.3048)
			(end 0.67945 -0.305054)
			(stroke
				(width 0.1)
				(type default)
			)
			(layer "B.Fab")
		)
		(pad "1" smd circle
			(at 0.40005 0 180)
			(size 0 0)
			(layers "B.Cu" "B.Mask" "B.Paste")
			(net "P3V3_AUX")
		)
		(pad "2" smd circle
			(at -0.40005 0 180)
			(size 0 0)
			(layers "B.Cu" "B.Mask" "B.Paste")
			(net "FM_PS_PWROK_DLY_R_SEL")
		)
	)
	(footprint ""
		(layer "B.Cu")
		(at 258.50088 -78.577948 90)
		(property "Reference" "PR1647"
			(at 0 0 90)
			(layer "B.SilkS")
			(hide yes)
			(effects
				(font
					(size 1.27 1.27)
				)
				(justify mirror)
			)
		)
		(property "Value" ""
			(at 0 0 90)
			(layer "B.Fab")
			(effects
				(font
					(size 1.27 1.27)
				)
				(justify mirror)
			)
		)
		(duplicate_pad_numbers_are_jumpers no)
		(fp_line
			(start 0.7874 -0.4064)
			(end -0.7874 -0.4064)
			(stroke
				(width 0.1524)
				(type default)
			)
			(layer "B.SilkS")
		)
		(fp_line
			(start -0.7874 -0.4064)
			(end -0.7874 0.4064)
			(stroke
				(width 0.1524)
				(type default)
			)
			(layer "B.SilkS")
		)
		(fp_line
			(start 0.7874 0.4064)
			(end 0.7874 -0.4064)
			(stroke
				(width 0.1524)
				(type default)
			)
			(layer "B.SilkS")
		)
		(fp_line
			(start -0.7874 0.4064)
			(end 0.7874 0.4064)
			(stroke
				(width 0.1524)
				(type default)
			)
			(layer "B.SilkS")
		)
		(fp_line
			(start 0.67945 -0.305054)
			(end 0.12065 -0.305054)
			(stroke
				(width 0.1)
				(type default)
			)
			(layer "B.Fab")
		)
		(fp_line
			(start 0.12065 -0.305054)
			(end 0.12065 -0.2794)
			(stroke
				(width 0.1)
				(type default)
			)
			(layer "B.Fab")
		)
		(fp_line
			(start -0.12065 -0.3048)
			(end -0.67945 -0.3048)
			(stroke
				(width 0.1)
				(type default)
			)
			(layer "B.Fab")
		)
		(fp_line
			(start -0.67945 -0.3048)
			(end -0.67945 0.3048)
			(stroke
				(width 0.1)
				(type default)
			)
			(layer "B.Fab")
		)
		(fp_line
			(start 0.12065 -0.2794)
			(end -0.12065 -0.2794)
			(stroke
				(width 0.1)
				(type default)
			)
			(layer "B.Fab")
		)
		(fp_line
			(start -0.12065 -0.2794)
			(end -0.12065 -0.3048)
			(stroke
				(width 0.1)
				(type default)
			)
			(layer "B.Fab")
		)
		(fp_line
			(start 0.12065 0.2794)
			(end 0.12065 0.3048)
			(stroke
				(width 0.1)
				(type default)
			)
			(layer "B.Fab")
		)
		(fp_line
			(start -0.120396 0.2794)
			(end 0.12065 0.2794)
			(stroke
				(width 0.1)
				(type default)
			)
			(layer "B.Fab")
		)
		(fp_line
			(start 0.67945 0.3048)
			(end 0.67945 -0.305054)
			(stroke
				(width 0.1)
				(type default)
			)
			(layer "B.Fab")
		)
		(fp_line
			(start 0.12065 0.3048)
			(end 0.67945 0.3048)
			(stroke
				(width 0.1)
				(type default)
			)
			(layer "B.Fab")
		)
		(fp_line
			(start -0.120396 0.3048)
			(end -0.120396 0.2794)
			(stroke
				(width 0.1)
				(type default)
			)
			(layer "B.Fab")
		)
		(fp_line
			(start -0.67945 0.3048)
			(end -0.120396 0.3048)
			(stroke
				(width 0.1)
				(type default)
			)
			(layer "B.Fab")
		)
		(pad "1" smd circle
			(at 0.40005 0 270)
			(size 0 0)
			(layers "B.Cu" "B.Mask" "B.Paste")
			(net "P3V3_AUX")
		)
		(pad "2" smd circle
			(at -0.40005 0 270)
			(size 0 0)
			(layers "B.Cu" "B.Mask" "B.Paste")
			(net "FM_P1V05_PCH_AUX_R_EN")
		)
	)
)
